(kicad_pcb
	(version 20260206)
	(generator "pcbnew")
	(generator_version "10.0")
	(general
		(thickness 1.6)
		(legacy_teardrops no)
	)
	(paper "A4")
	(title_block
		(title "Bryce Canyon_R.DPB_16317-1_OCP.brd")
		(comment 1 "Bryce Canyon / footprints 588-594 of 2099")
	)
	(layers
		(0 "F.Cu" signal "TOP")
		(4 "In1.Cu" signal "L2GND")
		(6 "In2.Cu" signal "L3")
		(8 "In3.Cu" signal "L4VCC")
		(10 "In4.Cu" signal "L5VCC")
		(12 "In5.Cu" signal "L6")
		(14 "In6.Cu" signal "L7GND")
		(2 "B.Cu" signal "BOTTOM")
		(9 "F.Adhes" user "F.Adhesive")
		(11 "B.Adhes" user "B.Adhesive")
		(13 "F.Paste" user "Package Geometry/Pastemask Top")
		(15 "B.Paste" user "Package Geometry/Pastemask Bottom")
		(5 "F.SilkS" user "Ref Des/Silkscreen Top")
		(7 "B.SilkS" user "Ref Des/Silkscreen Bottom")
		(1 "F.Mask" user "Board Geometry/Soldermask Top")
		(3 "B.Mask" user "Board Geometry/Soldermask Bottom")
		(17 "Dwgs.User" user "User.Drawings")
		(19 "Cmts.User" user "User.Comments")
		(21 "Eco1.User" user "User.Eco1")
		(23 "Eco2.User" user "User.Eco2")
		(25 "Edge.Cuts" user "Board Geometry/Outline")
		(27 "Margin" user)
		(31 "F.CrtYd" user "Package Geometry/Place Bound Top")
		(29 "B.CrtYd" user "Package Geometry/Place Bound Bottom")
		(35 "F.Fab" user "Ref Des/Assembly Top")
		(33 "B.Fab" user "Ref Des/Assembly Bottom")
	)
	(footprint ""
		(layer "F.Cu")
		(at 35.299396 -362.5596 180)
		(property "Reference" "R932"
			(at 0 0 180)
			(layer "F.SilkS")
			(hide yes)
			(effects
				(font
					(size 1.27 1.27)
				)
			)
		)
		(property "Value" "100KR2F-L1-GP"
			(at 0.064008 -3.993896 180)
			(unlocked yes)
			(layer "F.Fab")
			(hide yes)
			(effects
				(font
					(size 1.016 1.016)
					(thickness 0.1524)
				)
			)
		)
		(property "Device Type" "R402H16"
			(at 0.064008 -5.517896 180)
			(unlocked yes)
			(layer "F.Fab")
			(hide yes)
			(effects
				(font
					(size 1.016 1.016)
					(thickness 0.1524)
				)
			)
		)
		(duplicate_pad_numbers_are_jumpers no)
		(fp_line
			(start 0.508 -0.9398)
			(end -0.508 -0.9398)
			(stroke
				(width 0.1524)
				(type default)
			)
			(layer "F.SilkS")
		)
		(fp_line
			(start -0.508 -0.9398)
			(end -0.508 0.9398)
			(stroke
				(width 0.1524)
				(type default)
			)
			(layer "F.SilkS")
		)
		(fp_rect
			(start -0.508 0.9398)
			(end 0.508 -0.9398)
			(stroke
				(width 0)
				(type default)
			)
			(fill no)
			(layer "F.CrtYd")
		)
		(fp_rect
			(start -0.508 0.9398)
			(end 0.508 -0.9398)
			(stroke
				(width 0)
				(type default)
			)
			(fill no)
			(layer "F.Fab")
		)
		(pad "1" smd custom
			(at 0 -0.4445 180)
			(size 0.1397 0.1397)
			(layers "F.Cu" "F.Mask" "F.Paste")
			(net "SCC_A_FULL_PWR_EN")
			(options
				(clearance outline)
				(anchor circle)
			)
			(primitives
				(gr_poly
					(pts
						(arc
							(start -0.1778 -0.2794)
							(mid -0.249642 -0.249642)
							(end -0.2794 -0.1778)
						)
						(arc
							(start -0.2794 0.1778)
							(mid -0.249642 0.249642)
							(end -0.1778 0.2794)
						)
						(arc
							(start 0.1778 0.2794)
							(mid 0.249642 0.249642)
							(end 0.2794 0.1778)
						)
						(arc
							(start 0.2794 -0.1778)
							(mid 0.249642 -0.249642)
							(end 0.1778 -0.2794)
						)
					)
					(width 0)
					(fill yes)
				)
			)
		)
		(pad "2" smd custom
			(at 0 0.4445 180)
			(size 0.1397 0.1397)
			(layers "F.Cu" "F.Mask" "F.Paste")
			(net "GND")
			(options
				(clearance outline)
				(anchor circle)
			)
			(primitives
				(gr_poly
					(pts
						(arc
							(start -0.1778 -0.2794)
							(mid -0.249642 -0.249642)
							(end -0.2794 -0.1778)
						)
						(arc
							(start -0.2794 0.1778)
							(mid -0.249642 0.249642)
							(end -0.1778 0.2794)
						)
						(arc
							(start 0.1778 0.2794)
							(mid 0.249642 0.249642)
							(end 0.2794 0.1778)
						)
						(arc
							(start 0.2794 -0.1778)
							(mid 0.249642 -0.249642)
							(end 0.1778 -0.2794)
						)
					)
					(width 0)
					(fill yes)
				)
			)
		)
	)
	(footprint ""
		(layer "F.Cu")
		(at 257.331972 -335.277206 90)
		(property "Reference" "Q203"
			(at 0 0 90)
			(layer "F.SilkS")
			(hide yes)
			(effects
				(font
					(size 1.27 1.27)
				)
			)
		)
		(property "Value" "IRFH8201TRPBF-GP"
			(at -4.2164 -4.3688 90)
			(unlocked yes)
			(layer "F.Fab")
			(hide yes)
			(effects
				(font
					(size 1.016 1.016)
					(thickness 0.1524)
				)
			)
		)
		(property "Device Type" "PPAK-5PH42"
			(at -4.2164 -5.8928 90)
			(unlocked yes)
			(layer "F.Fab")
			(hide yes)
			(effects
				(font
					(size 1.016 1.016)
					(thickness 0.1524)
				)
			)
		)
		(duplicate_pad_numbers_are_jumpers no)
		(fp_line
			(start 2.8956 -2.794)
			(end 2.8956 4.826)
			(stroke
				(width 0.1524)
				(type default)
			)
			(layer "F.SilkS")
		)
		(fp_line
			(start -2.8956 -2.794)
			(end 2.8956 -2.794)
			(stroke
				(width 0.1524)
				(type default)
			)
			(layer "F.SilkS")
		)
		(fp_line
			(start 2.8956 4.826)
			(end -2.8956 4.826)
			(stroke
				(width 0.1524)
				(type default)
			)
			(layer "F.SilkS")
		)
		(fp_line
			(start -2.8956 4.826)
			(end -2.8956 -2.794)
			(stroke
				(width 0.1524)
				(type default)
			)
			(layer "F.SilkS")
		)
		(fp_line
			(start -1.9431 4.9276)
			(end -3.0353 4.9276)
			(stroke
				(width 0.3302)
				(type default)
			)
			(layer "F.SilkS")
		)
		(fp_line
			(start -3.0353 4.9276)
			(end -3.0353 3.9624)
			(stroke
				(width 0.3302)
				(type default)
			)
			(layer "F.SilkS")
		)
		(fp_poly
			(pts
				(xy -2.3622 5.334) (xy -1.4986 5.334) (xy -1.9304 4.9022)
			)
			(stroke
				(width 0)
				(type default)
			)
			(fill yes)
			(layer "F.SilkS")
		)
		(fp_poly
			(pts
				(xy 0.3556 -0.3556) (xy 2.6416 -0.3556) (xy 2.6416 -2.54) (xy 0.3556 -2.54)
			)
			(stroke
				(width 0)
				(type default)
			)
			(fill yes)
			(layer "F.Paste")
		)
		(fp_poly
			(pts
				(xy -2.6416 -0.3556) (xy -0.3556 -0.3556) (xy -0.3556 -2.54) (xy -2.6416 -2.54)
			)
			(stroke
				(width 0)
				(type default)
			)
			(fill yes)
			(layer "F.Paste")
		)
		(fp_poly
			(pts
				(xy 0.3556 2.54) (xy 2.6416 2.54) (xy 2.6416 0.3556) (xy 0.3556 0.3556)
			)
			(stroke
				(width 0)
				(type default)
			)
			(fill yes)
			(layer "F.Paste")
		)
		(fp_poly
			(pts
				(xy -2.6416 2.54) (xy -0.3556 2.54) (xy -0.3556 0.3556) (xy -2.6416 0.3556)
			)
			(stroke
				(width 0)
				(type default)
			)
			(fill yes)
			(layer "F.Paste")
		)
		(fp_rect
			(start -2.5781 3.9878)
			(end 2.5781 -2.1082)
			(stroke
				(width 0)
				(type default)
			)
			(fill no)
			(layer "F.CrtYd")
		)
		(fp_poly
			(pts
				(xy -3.1496 5.08) (xy -3.1496 -3.048) (xy 3.1496 -3.048) (xy 3.1496 3.9751) (xy 2.5781 3.9751) (xy 2.5781 -2.1082)
				(xy -2.5781 -2.1082) (xy -2.5781 3.9878) (xy 3.1496 3.9878) (xy 3.1496 5.08)
			)
			(stroke
				(width 0)
				(type default)
			)
			(fill no)
			(layer "F.CrtYd")
		)
		(fp_rect
			(start -3.1496 5.08)
			(end 3.1496 -3.048)
			(stroke
				(width 0)
				(type default)
			)
			(fill no)
			(layer "F.Fab")
		)
		(pad "1" smd rect
			(at -1.905 3.81 90)
			(size 0.762 1.524)
			(layers "F.Cu" "F.Mask" "F.Paste")
			(net "P12V_B")
		)
		(pad "2" smd rect
			(at -0.635 3.81 90)
			(size 0.762 1.524)
			(layers "F.Cu" "F.Mask" "F.Paste")
			(net "P12V_B")
		)
		(pad "3" smd rect
			(at 0.635 3.81 90)
			(size 0.762 1.524)
			(layers "F.Cu" "F.Mask" "F.Paste")
			(net "P12V_B")
		)
		(pad "4" smd rect
			(at 1.905 3.81 90)
			(size 0.762 1.524)
			(layers "F.Cu" "F.Mask" "F.Paste")
			(net "MB3_12V_CTRL_GATE3")
		)
		(pad "5" smd rect
			(at 0 0 90)
			(size 5.2832 5.08)
			(layers "F.Cu" "F.Mask" "F.Paste")
			(net "MB3_P12V_IN_R")
		)
		(pad "6" smd rect
			(at 0.635 -2.032 90)
			(size 0.0254 0.0254)
			(layers "F.Cu" "F.Mask" "F.Paste")
			(net "MB3_P12V_IN_R")
		)
		(pad "7" smd rect
			(at -0.635 -2.032 90)
			(size 0.0254 0.0254)
			(layers "F.Cu" "F.Mask" "F.Paste")
			(net "MB3_P12V_IN_R")
		)
		(pad "8" smd rect
			(at -1.905 -2.032 90)
			(size 0.0254 0.0254)
			(layers "F.Cu" "F.Mask" "F.Paste")
			(net "MB3_P12V_IN_R")
		)
	)
	(footprint ""
		(layer "F.Cu")
		(at 207.3402 -194.945 -90)
		(property "Reference" "R32"
			(at 0 0 270)
			(layer "F.SilkS")
			(hide yes)
			(effects
				(font
					(size 1.27 1.27)
				)
			)
		)
		(property "Value" "4K7R2F-GP"
			(at 0.064008 -3.993896 270)
			(unlocked yes)
			(layer "F.Fab")
			(hide yes)
			(effects
				(font
					(size 1.016 1.016)
					(thickness 0.1524)
				)
			)
		)
		(property "Device Type" "R402H16"
			(at 0.064008 -5.517896 270)
			(unlocked yes)
			(layer "F.Fab")
			(hide yes)
			(effects
				(font
					(size 1.016 1.016)
					(thickness 0.1524)
				)
			)
		)
		(duplicate_pad_numbers_are_jumpers no)
		(fp_line
			(start -0.508 -0.9398)
			(end -0.508 0.9398)
			(stroke
				(width 0.1524)
				(type default)
			)
			(layer "F.SilkS")
		)
		(fp_line
			(start 0.508 -0.9398)
			(end -0.508 -0.9398)
			(stroke
				(width 0.1524)
				(type default)
			)
			(layer "F.SilkS")
		)
		(fp_rect
			(start -0.508 0.9398)
			(end 0.508 -0.9398)
			(stroke
				(width 0)
				(type default)
			)
			(fill no)
			(layer "F.CrtYd")
		)
		(fp_rect
			(start -0.508 0.9398)
			(end 0.508 -0.9398)
			(stroke
				(width 0)
				(type default)
			)
			(fill no)
			(layer "F.Fab")
		)
		(pad "1" smd custom
			(at 0 -0.4445 270)
			(size 0.1397 0.1397)
			(layers "F.Cu" "F.Mask" "F.Paste")
			(net "IO_EXP2_HDD_FAULT_A2")
			(options
				(clearance outline)
				(anchor circle)
			)
			(primitives
				(gr_poly
					(pts
						(arc
							(start -0.1778 -0.2794)
							(mid -0.249642 -0.249642)
							(end -0.2794 -0.1778)
						)
						(arc
							(start -0.2794 0.1778)
							(mid -0.249642 0.249642)
							(end -0.1778 0.2794)
						)
						(arc
							(start 0.1778 0.2794)
							(mid 0.249642 0.249642)
							(end 0.2794 0.1778)
						)
						(arc
							(start 0.2794 -0.1778)
							(mid 0.249642 -0.249642)
							(end 0.1778 -0.2794)
						)
					)
					(width 0)
					(fill yes)
				)
			)
		)
		(pad "2" smd custom
			(at 0 0.4445 270)
			(size 0.1397 0.1397)
			(layers "F.Cu" "F.Mask" "F.Paste")
			(net "GND")
			(options
				(clearance outline)
				(anchor circle)
			)
			(primitives
				(gr_poly
					(pts
						(arc
							(start -0.1778 -0.2794)
							(mid -0.249642 -0.249642)
							(end -0.2794 -0.1778)
						)
						(arc
							(start -0.2794 0.1778)
							(mid -0.249642 0.249642)
							(end -0.1778 0.2794)
						)
						(arc
							(start 0.1778 0.2794)
							(mid 0.249642 0.249642)
							(end 0.2794 0.1778)
						)
						(arc
							(start 0.2794 -0.1778)
							(mid 0.249642 -0.249642)
							(end 0.1778 -0.2794)
						)
					)
					(width 0)
					(fill yes)
				)
			)
		)
	)
	(footprint ""
		(layer "F.Cu")
		(at 394.6398 -17.6022 90)
		(property "Reference" "R813"
			(at 0 0 90)
			(layer "F.SilkS")
			(hide yes)
			(effects
				(font
					(size 1.27 1.27)
				)
			)
		)
		(property "Value" "4K7R2J-2-GP"
			(at 0.064008 -3.993896 90)
			(unlocked yes)
			(layer "F.Fab")
			(hide yes)
			(effects
				(font
					(size 1.016 1.016)
					(thickness 0.1524)
				)
			)
		)
		(property "Device Type" "R402H16"
			(at 0.064008 -5.517896 90)
			(unlocked yes)
			(layer "F.Fab")
			(hide yes)
			(effects
				(font
					(size 1.016 1.016)
					(thickness 0.1524)
				)
			)
		)
		(duplicate_pad_numbers_are_jumpers no)
		(fp_line
			(start 0.508 -0.9398)
			(end -0.508 -0.9398)
			(stroke
				(width 0.1524)
				(type default)
			)
			(layer "F.SilkS")
		)
		(fp_line
			(start -0.508 -0.9398)
			(end -0.508 0.9398)
			(stroke
				(width 0.1524)
				(type default)
			)
			(layer "F.SilkS")
		)
		(fp_rect
			(start -0.508 0.9398)
			(end 0.508 -0.9398)
			(stroke
				(width 0)
				(type default)
			)
			(fill no)
			(layer "F.CrtYd")
		)
		(fp_rect
			(start -0.508 0.9398)
			(end 0.508 -0.9398)
			(stroke
				(width 0)
				(type default)
			)
			(fill no)
			(layer "F.Fab")
		)
		(pad "1" smd custom
			(at 0 -0.4445 90)
			(size 0.1397 0.1397)
			(layers "F.Cu" "F.Mask" "F.Paste")
			(net "P12V_B")
			(options
				(clearance outline)
				(anchor circle)
			)
			(primitives
				(gr_poly
					(pts
						(arc
							(start -0.1778 -0.2794)
							(mid -0.249642 -0.249642)
							(end -0.2794 -0.1778)
						)
						(arc
							(start -0.2794 0.1778)
							(mid -0.249642 0.249642)
							(end -0.1778 0.2794)
						)
						(arc
							(start 0.1778 0.2794)
							(mid 0.249642 0.249642)
							(end 0.2794 0.1778)
						)
						(arc
							(start 0.2794 -0.1778)
							(mid 0.249642 -0.249642)
							(end 0.1778 -0.2794)
						)
					)
					(width 0)
					(fill yes)
				)
			)
		)
		(pad "2" smd custom
			(at 0 0.4445 90)
			(size 0.1397 0.1397)
			(layers "F.Cu" "F.Mask" "F.Paste")
			(net "SW_HDD_P32")
			(options
				(clearance outline)
				(anchor circle)
			)
			(primitives
				(gr_poly
					(pts
						(arc
							(start -0.1778 -0.2794)
							(mid -0.249642 -0.249642)
							(end -0.2794 -0.1778)
						)
						(arc
							(start -0.2794 0.1778)
							(mid -0.249642 0.249642)
							(end -0.1778 0.2794)
						)
						(arc
							(start 0.1778 0.2794)
							(mid 0.249642 0.249642)
							(end 0.2794 0.1778)
						)
						(arc
							(start 0.2794 -0.1778)
							(mid 0.249642 -0.249642)
							(end 0.1778 -0.2794)
						)
					)
					(width 0)
					(fill yes)
				)
			)
		)
	)
	(footprint ""
		(layer "F.Cu")
		(at 66.313812 -269.705074)
		(property "Reference" "TP26"
			(at 0 0 0)
			(layer "F.SilkS")
			(hide yes)
			(effects
				(font
					(size 1.27 1.27)
				)
			)
		)
		(property "Value" "*"
			(at -0.0508 -1.6764 0)
			(unlocked yes)
			(layer "F.Fab")
			(hide yes)
			(effects
				(font
					(size 1.016 1.016)
					(thickness 0.1524)
				)
			)
		)
		(property "Device Type" "TPAD32"
			(at -0.0508 -3.2004 0)
			(unlocked yes)
			(layer "F.Fab")
			(hide yes)
			(effects
				(font
					(size 1.016 1.016)
					(thickness 0.1524)
				)
			)
		)
		(duplicate_pad_numbers_are_jumpers no)
		(fp_poly
			(pts
				(arc
					(start 0.4064 0)
					(mid -0.4064 0)
					(end 0.4064 0)
				)
			)
			(stroke
				(width 0)
				(type default)
			)
			(fill no)
			(layer "F.CrtYd")
		)
		(fp_poly
			(pts
				(arc
					(start 0.7112 0)
					(mid -0.7112 0)
					(end 0.7112 0)
				)
			)
			(stroke
				(width 0)
				(type default)
			)
			(fill no)
			(layer "F.Fab")
		)
		(pad "1" smd circle
			(at 0 0)
			(size 0.8128 0.8128)
			(layers "F.Cu" "F.Mask" "F.Paste")
			(net "ACT_HDD_1")
		)
	)
	(footprint ""
		(layer "F.Cu")
		(at 456.674982 -178.799998)
		(property "Reference" ""
			(at 0 0 0)
			(layer "F.SilkS")
			(hide yes)
			(effects
				(font
					(size 1.27 1.27)
				)
			)
		)
		(property "Value" "*"
			(at -8.398764 -8.057642 0)
			(unlocked yes)
			(layer "F.Fab")
			(hide yes)
			(effects
				(font
					(size 1.016 1.016)
					(thickness 0.1524)
				)
			)
		)
		(duplicate_pad_numbers_are_jumpers no)
		(fp_poly
			(pts
				(arc
					(start 7.3152 0)
					(mid 0 7.3152)
					(end -7.3152 0)
				)
				(arc
					(start -7.3152 -5.9944)
					(mid 0 -13.3096)
					(end 7.3152 -5.9944)
				)
			)
			(stroke
				(width 0)
				(type default)
			)
			(fill no)
			(layer "B.CrtYd")
		)
		(fp_poly
			(pts
				(arc
					(start 7.3152 0)
					(mid 0 7.3152)
					(end -7.3152 0)
				)
				(arc
					(start -7.3152 -5.9944)
					(mid 0 -13.3096)
					(end 7.3152 -5.9944)
				)
			)
			(stroke
				(width 0)
				(type default)
			)
			(fill no)
			(layer "F.CrtYd")
		)
		(fp_poly
			(pts
				(arc
					(start 7.3152 0)
					(mid 0 7.3152)
					(end -7.3152 0)
				)
				(arc
					(start -7.3152 -5.9944)
					(mid 0 -13.3096)
					(end 7.3152 -5.9944)
				)
			)
			(stroke
				(width 0)
				(type default)
			)
			(fill no)
			(layer "B.Fab")
		)
		(fp_poly
			(pts
				(arc
					(start 7.3152 0)
					(mid 0 7.3152)
					(end -7.3152 0)
				)
				(arc
					(start -7.3152 -5.9944)
					(mid 0 -13.3096)
					(end 7.3152 -5.9944)
				)
			)
			(stroke
				(width 0)
				(type default)
			)
			(fill no)
			(layer "F.Fab")
		)
		(pad "1" thru_hole oval
			(at 0 0)
			(size 14.0208 20.0152)
			(drill 0.0254
				(offset 0 -2.9972)
			)
			(layers "*.Cu" "*.Mask")
			(remove_unused_layers no)
			(net "Net_42")
			(clearance -1.002284)
			(thermal_gap 0.1524)
			(padstack
				(mode front_inner_back)
				(layer "Inner"
					(shape custom)
					(size 2.928012 2.928012)
					(options
						(anchor circle)
					)
					(primitives
						(gr_poly
							(pts
								(arc
									(start 4.571746 -2.084324)
									(mid 0.000333 7.430372)
									(end -4.571492 -2.084324)
								)
								(arc
									(start -4.571492 -2.084324)
									(mid -3.570296 -3.611977)
									(end -2.875026 -5.30098)
								)
								(arc
									(start -2.875026 -5.30098)
									(mid 0.000217 -7.43089)
									(end 2.87528 -5.30098)
								)
								(arc
									(start 2.87528 -5.30098)
									(mid 3.570511 -3.611956)
									(end 4.571746 -2.084324)
								)
							)
							(width 0)
							(fill yes)
						)
					)
					(clearance 0.1524)
				)
				(layer "B.Cu"
					(shape oval)
					(size 14.0208 20.0152)
					(offset 0 -2.9972)
					(clearance -1.002284)
				)
			)
		)
		(zone
			(layers "F.Cu" "B.Cu" "In1.Cu" "In2.Cu" "In3.Cu" "In4.Cu" "In5.Cu" "In6.Cu")
			(hatch none 0.5)
			(connect_pads
				(clearance 0)
			)
			(min_thickness 0.25)
			(keepout
				(tracks not_allowed)
				(vias allowed)
				(pads allowed)
				(copperpour not_allowed)
				(footprints allowed)
			)
			(placement
				(enabled no)
				(sheetname "")
			)
			(fill
				(thermal_gap 0.5)
				(thermal_bridge_width 0.5)
				(island_removal_mode 0)
			)
			(polygon
				(pts
					(arc
						(start 449.664582 -184.794398)
						(mid 456.674982 -191.804798)
						(end 463.685382 -184.794398)
					)
					(arc
						(start 463.685382 -178.799998)
						(mid 456.674982 -171.789598)
						(end 449.664582 -178.799998)
					)
				)
			)
		)
	)
	(footprint ""
		(layer "F.Cu")
		(at 331.089 -12.827 -90)
		(property "Reference" "Q155"
			(at 0 0 270)
			(layer "F.SilkS")
			(hide yes)
			(effects
				(font
					(size 1.27 1.27)
				)
			)
		)
		(property "Value" "2N7002KDW-GP"
			(at -2.3622 -8.2042 270)
			(unlocked yes)
			(layer "F.Fab")
			(hide yes)
			(effects
				(font
					(size 1.016 1.016)
					(thickness 0.1524)
				)
			)
		)
		(property "Device Type" "SOT-363H44"
			(at -2.3622 -10.1092 270)
			(unlocked yes)
			(layer "F.Fab")
			(hide yes)
			(effects
				(font
					(size 1.016 1.016)
					(thickness 0.1524)
				)
			)
		)
		(duplicate_pad_numbers_are_jumpers no)
		(fp_line
			(start -1.4478 1.7018)
			(end 1.4478 1.7018)
			(stroke
				(width 0.1524)
				(type default)
			)
			(layer "F.SilkS")
		)
		(fp_line
			(start 1.4478 1.7018)
			(end 1.4478 -1.7018)
			(stroke
				(width 0.1524)
				(type default)
			)
			(layer "F.SilkS")
		)
		(fp_line
			(start -1.27 1.524)
			(end -1.27 0.6604)
			(stroke
				(width 0.4826)
				(type default)
			)
			(layer "F.SilkS")
		)
		(fp_line
			(start -1.4478 -1.7018)
			(end -1.4478 1.7018)
			(stroke
				(width 0.1524)
				(type default)
			)
			(layer "F.SilkS")
		)
		(fp_line
			(start 1.4478 -1.7018)
			(end -1.4478 -1.7018)
			(stroke
				(width 0.1524)
				(type default)
			)
			(layer "F.SilkS")
		)
		(fp_poly
			(pts
				(xy -1.524 -1.778) (xy 1.524 -1.778) (xy 1.524 1.778) (xy -1.524 1.778)
			)
			(stroke
				(width 0)
				(type default)
			)
			(fill no)
			(layer "F.CrtYd")
		)
		(fp_poly
			(pts
				(xy -1.524 -1.778) (xy 1.524 -1.778) (xy 1.524 1.778) (xy -1.524 1.778)
			)
			(stroke
				(width 0)
				(type default)
			)
			(fill no)
			(layer "F.Fab")
		)
		(pad "1" smd rect
			(at -0.65024 0.9398 270)
			(size 0.4064 1.016)
			(layers "F.Cu" "F.Mask" "F.Paste")
			(net "GND")
		)
		(pad "2" smd rect
			(at 0 0.9398 270)
			(size 0.4064 1.016)
			(layers "F.Cu" "F.Mask" "F.Paste")
			(net "SW_PWR_R_HDD30")
		)
		(pad "3" smd rect
			(at 0.65024 0.9398 270)
			(size 0.4064 1.016)
			(layers "F.Cu" "F.Mask" "F.Paste")
			(net "SW_HDD_P30")
		)
		(pad "4" smd rect
			(at 0.65024 -0.9398 270)
			(size 0.4064 1.016)
			(layers "F.Cu" "F.Mask" "F.Paste")
			(net "GND")
		)
		(pad "5" smd rect
			(at 0 -0.9398 270)
			(size 0.4064 1.016)
			(layers "F.Cu" "F.Mask" "F.Paste")
			(net "SW_HDD_G30")
		)
		(pad "6" smd rect
			(at -0.65024 -0.9398 270)
			(size 0.4064 1.016)
			(layers "F.Cu" "F.Mask" "F.Paste")
			(net "SW_HDD_R30")
		)
	)
)
